(kicad_pcb
	(version 20260206)
	(generator "pcbnew")
	(generator_version "10.0")
	(general
		(thickness 1.6)
		(legacy_teardrops no)
	)
	(paper "A4")
	(title_block
		(title "04192023_DAF0TMB3IC0_F0TG_MB_C_brd_V02_OCP.brd")
		(comment 1 "Grand Teton / footprints 7547-7553 of 8354")
	)
	(layers
		(0 "F.Cu" signal "TOP")
		(4 "In1.Cu" signal "GND")
		(6 "In2.Cu" signal "IN1")
		(8 "In3.Cu" signal "GND1")
		(10 "In4.Cu" signal "IN2")
		(12 "In5.Cu" signal "GND2")
		(14 "In6.Cu" signal "IN3")
		(16 "In7.Cu" signal "GND3")
		(18 "In8.Cu" signal "VCC")
		(20 "In9.Cu" signal "VCC1")
		(22 "In10.Cu" signal "GND4")
		(24 "In11.Cu" signal "IN4")
		(26 "In12.Cu" signal "GND5")
		(28 "In13.Cu" signal "IN5")
		(30 "In14.Cu" signal "GND6")
		(32 "In15.Cu" signal "IN6")
		(34 "In16.Cu" signal "GND7")
		(2 "B.Cu" signal "BOTTOM")
		(9 "F.Adhes" user "F.Adhesive")
		(11 "B.Adhes" user "B.Adhesive")
		(13 "F.Paste" user "Package Geometry/Pastemask Top")
		(15 "B.Paste" user "Package Geometry/Pastemask Bottom")
		(5 "F.SilkS" user "Ref Des/Silkscreen Top")
		(7 "B.SilkS" user "Ref Des/Silkscreen Bottom")
		(1 "F.Mask" user "Board Geometry/Soldermask Top")
		(3 "B.Mask" user "Board Geometry/Soldermask Bottom")
		(17 "Dwgs.User" user "User.Drawings")
		(19 "Cmts.User" user "User.Comments")
		(21 "Eco1.User" user "User.Eco1")
		(23 "Eco2.User" user "User.Eco2")
		(25 "Edge.Cuts" user "Board Geometry/Outline")
		(27 "Margin" user)
		(31 "F.CrtYd" user "Package Geometry/Place Bound Top")
		(29 "B.CrtYd" user "Package Geometry/Place Bound Bottom")
		(35 "F.Fab" user "Ref Des/Assembly Top")
		(33 "B.Fab" user "Ref Des/Assembly Bottom")
	)
	(footprint ""
		(layer "B.Cu")
		(at 163.423092 -417.295584)
		(property "Reference" "R1200"
			(at 0 0 0)
			(layer "B.SilkS")
			(hide yes)
			(effects
				(font
					(size 1.27 1.27)
				)
				(justify mirror)
			)
		)
		(property "Value" ""
			(at 0 0 0)
			(layer "B.Fab")
			(effects
				(font
					(size 1.27 1.27)
				)
				(justify mirror)
			)
		)
		(duplicate_pad_numbers_are_jumpers no)
		(fp_line
			(start -0.32512 -0.175006)
			(end -0.32512 0.175006)
			(stroke
				(width 0.1)
				(type default)
			)
			(layer "B.Fab")
		)
		(fp_line
			(start -0.32512 0.175006)
			(end 0.32512 0.175006)
			(stroke
				(width 0.1)
				(type default)
			)
			(layer "B.Fab")
		)
		(fp_line
			(start 0.32512 -0.175006)
			(end -0.32512 -0.175006)
			(stroke
				(width 0.1)
				(type default)
			)
			(layer "B.Fab")
		)
		(fp_line
			(start 0.32512 0.175006)
			(end 0.32512 -0.175006)
			(stroke
				(width 0.1)
				(type default)
			)
			(layer "B.Fab")
		)
		(pad "1" smd rect
			(at 0.2667 0 180)
			(size 0.3048 0.381)
			(layers "B.Cu" "B.Mask" "B.Paste")
			(net "RST_SMB_RT_ROM_R1_N")
		)
		(pad "2" smd rect
			(at -0.2667 0)
			(size 0.3048 0.381)
			(layers "B.Cu" "B.Mask" "B.Paste")
			(net "FM_SMB_RT_ROM_MUX4_SEL")
		)
	)
	(footprint ""
		(layer "B.Cu")
		(at 187.585096 -353.986084 -90)
		(property "Reference" "PR333"
			(at 0 0 90)
			(layer "B.SilkS")
			(hide yes)
			(effects
				(font
					(size 1.27 1.27)
				)
				(justify mirror)
			)
		)
		(property "Value" ""
			(at 0 0 90)
			(layer "B.Fab")
			(effects
				(font
					(size 1.27 1.27)
				)
				(justify mirror)
			)
		)
		(duplicate_pad_numbers_are_jumpers no)
		(fp_line
			(start -0.7874 0.4064)
			(end 0.7874 0.4064)
			(stroke
				(width 0.1524)
				(type default)
			)
			(layer "B.SilkS")
		)
		(fp_line
			(start 0.7874 0.4064)
			(end 0.7874 -0.4064)
			(stroke
				(width 0.1524)
				(type default)
			)
			(layer "B.SilkS")
		)
		(fp_line
			(start -0.7874 -0.4064)
			(end -0.7874 0.4064)
			(stroke
				(width 0.1524)
				(type default)
			)
			(layer "B.SilkS")
		)
		(fp_line
			(start 0.7874 -0.4064)
			(end -0.7874 -0.4064)
			(stroke
				(width 0.1524)
				(type default)
			)
			(layer "B.SilkS")
		)
		(fp_line
			(start -0.67945 0.3048)
			(end -0.120396 0.3048)
			(stroke
				(width 0.1)
				(type default)
			)
			(layer "B.Fab")
		)
		(fp_line
			(start -0.120396 0.3048)
			(end -0.120396 0.2794)
			(stroke
				(width 0.1)
				(type default)
			)
			(layer "B.Fab")
		)
		(fp_line
			(start 0.12065 0.3048)
			(end 0.67945 0.3048)
			(stroke
				(width 0.1)
				(type default)
			)
			(layer "B.Fab")
		)
		(fp_line
			(start 0.67945 0.3048)
			(end 0.67945 -0.305054)
			(stroke
				(width 0.1)
				(type default)
			)
			(layer "B.Fab")
		)
		(fp_line
			(start -0.120396 0.2794)
			(end 0.12065 0.2794)
			(stroke
				(width 0.1)
				(type default)
			)
			(layer "B.Fab")
		)
		(fp_line
			(start 0.12065 0.2794)
			(end 0.12065 0.3048)
			(stroke
				(width 0.1)
				(type default)
			)
			(layer "B.Fab")
		)
		(fp_line
			(start -0.12065 -0.2794)
			(end -0.12065 -0.3048)
			(stroke
				(width 0.1)
				(type default)
			)
			(layer "B.Fab")
		)
		(fp_line
			(start 0.12065 -0.2794)
			(end -0.12065 -0.2794)
			(stroke
				(width 0.1)
				(type default)
			)
			(layer "B.Fab")
		)
		(fp_line
			(start -0.67945 -0.3048)
			(end -0.67945 0.3048)
			(stroke
				(width 0.1)
				(type default)
			)
			(layer "B.Fab")
		)
		(fp_line
			(start -0.12065 -0.3048)
			(end -0.67945 -0.3048)
			(stroke
				(width 0.1)
				(type default)
			)
			(layer "B.Fab")
		)
		(fp_line
			(start 0.12065 -0.305054)
			(end 0.12065 -0.2794)
			(stroke
				(width 0.1)
				(type default)
			)
			(layer "B.Fab")
		)
		(fp_line
			(start 0.67945 -0.305054)
			(end 0.12065 -0.305054)
			(stroke
				(width 0.1)
				(type default)
			)
			(layer "B.Fab")
		)
		(pad "1" smd circle
			(at 0.40005 0 90)
			(size 0 0)
			(layers "B.Cu" "B.Mask" "B.Paste")
			(net "PVDD11_S3_P1_VOS2")
		)
		(pad "2" smd circle
			(at -0.40005 0 90)
			(size 0 0)
			(layers "B.Cu" "B.Mask" "B.Paste")
			(net "PVDD11_S3_P1")
		)
	)
	(footprint ""
		(layer "B.Cu")
		(at 378.957586 -214.523828 90)
		(property "Reference" "R9275"
			(at 0 0 90)
			(layer "B.SilkS")
			(hide yes)
			(effects
				(font
					(size 1.27 1.27)
				)
				(justify mirror)
			)
		)
		(property "Value" ""
			(at 0 0 90)
			(layer "B.Fab")
			(effects
				(font
					(size 1.27 1.27)
				)
				(justify mirror)
			)
		)
		(duplicate_pad_numbers_are_jumpers no)
		(fp_line
			(start 0.360172 -0.4064)
			(end -0.376428 -0.4064)
			(stroke
				(width 0.1524)
				(type default)
			)
			(layer "B.SilkS")
		)
		(fp_line
			(start -0.7874 0.086614)
			(end -0.7874 0.4064)
			(stroke
				(width 0.1524)
				(type default)
			)
			(layer "B.SilkS")
		)
		(fp_line
			(start 0.7874 0.4064)
			(end 0.7874 0.010414)
			(stroke
				(width 0.1524)
				(type default)
			)
			(layer "B.SilkS")
		)
		(fp_line
			(start -0.7874 0.4064)
			(end 0.7874 0.4064)
			(stroke
				(width 0.1524)
				(type default)
			)
			(layer "B.SilkS")
		)
		(fp_line
			(start 0.67945 -0.305054)
			(end 0.12065 -0.305054)
			(stroke
				(width 0.1)
				(type default)
			)
			(layer "B.Fab")
		)
		(fp_line
			(start 0.12065 -0.305054)
			(end 0.12065 -0.2794)
			(stroke
				(width 0.1)
				(type default)
			)
			(layer "B.Fab")
		)
		(fp_line
			(start -0.12065 -0.3048)
			(end -0.67945 -0.3048)
			(stroke
				(width 0.1)
				(type default)
			)
			(layer "B.Fab")
		)
		(fp_line
			(start -0.67945 -0.3048)
			(end -0.67945 0.3048)
			(stroke
				(width 0.1)
				(type default)
			)
			(layer "B.Fab")
		)
		(fp_line
			(start 0.12065 -0.2794)
			(end -0.12065 -0.2794)
			(stroke
				(width 0.1)
				(type default)
			)
			(layer "B.Fab")
		)
		(fp_line
			(start -0.12065 -0.2794)
			(end -0.12065 -0.3048)
			(stroke
				(width 0.1)
				(type default)
			)
			(layer "B.Fab")
		)
		(fp_line
			(start 0.12065 0.2794)
			(end 0.12065 0.3048)
			(stroke
				(width 0.1)
				(type default)
			)
			(layer "B.Fab")
		)
		(fp_line
			(start -0.120396 0.2794)
			(end 0.12065 0.2794)
			(stroke
				(width 0.1)
				(type default)
			)
			(layer "B.Fab")
		)
		(fp_line
			(start 0.67945 0.3048)
			(end 0.67945 -0.305054)
			(stroke
				(width 0.1)
				(type default)
			)
			(layer "B.Fab")
		)
		(fp_line
			(start 0.12065 0.3048)
			(end 0.67945 0.3048)
			(stroke
				(width 0.1)
				(type default)
			)
			(layer "B.Fab")
		)
		(fp_line
			(start -0.120396 0.3048)
			(end -0.120396 0.2794)
			(stroke
				(width 0.1)
				(type default)
			)
			(layer "B.Fab")
		)
		(fp_line
			(start -0.67945 0.3048)
			(end -0.120396 0.3048)
			(stroke
				(width 0.1)
				(type default)
			)
			(layer "B.Fab")
		)
		(pad "1" smd circle
			(at 0.40005 0 270)
			(size 0 0)
			(layers "B.Cu" "B.Mask" "B.Paste")
			(net "CLK_100M_CPU0_CLK05_R_DP")
		)
		(pad "2" smd circle
			(at -0.40005 0 270)
			(size 0 0)
			(layers "B.Cu" "B.Mask" "B.Paste")
			(net "CLK_100M_CPU0_CLK05_DP")
		)
	)
	(footprint ""
		(layer "B.Cu")
		(at 392.695938 -195.830952 90)
		(property "Reference" "PC563_4"
			(at 0 0 90)
			(layer "B.SilkS")
			(hide yes)
			(effects
				(font
					(size 1.27 1.27)
				)
				(justify mirror)
			)
		)
		(property "Value" ""
			(at 0 0 90)
			(layer "B.Fab")
			(effects
				(font
					(size 1.27 1.27)
				)
				(justify mirror)
			)
		)
		(duplicate_pad_numbers_are_jumpers no)
		(fp_line
			(start 1.524 -0.762)
			(end -1.524 -0.762)
			(stroke
				(width 0.1524)
				(type default)
			)
			(layer "B.SilkS")
		)
		(fp_line
			(start -1.524 -0.762)
			(end -1.524 0.762)
			(stroke
				(width 0.1524)
				(type default)
			)
			(layer "B.SilkS")
		)
		(fp_line
			(start 1.524 0.762)
			(end 1.524 -0.762)
			(stroke
				(width 0.1524)
				(type default)
			)
			(layer "B.SilkS")
		)
		(fp_line
			(start -1.524 0.762)
			(end 1.524 0.762)
			(stroke
				(width 0.1524)
				(type default)
			)
			(layer "B.SilkS")
		)
		(fp_line
			(start 1.1049 -0.724916)
			(end 1.1049 0.724916)
			(stroke
				(width 0.1)
				(type default)
			)
			(layer "B.Fab")
		)
		(fp_line
			(start -1.1049 -0.724916)
			(end 1.1049 -0.724916)
			(stroke
				(width 0.1)
				(type default)
			)
			(layer "B.Fab")
		)
		(fp_line
			(start 1.1049 0.724916)
			(end -1.1049 0.724916)
			(stroke
				(width 0.1)
				(type default)
			)
			(layer "B.Fab")
		)
		(fp_line
			(start -1.1049 0.724916)
			(end -1.1049 -0.724916)
			(stroke
				(width 0.1)
				(type default)
			)
			(layer "B.Fab")
		)
		(pad "1" smd rect
			(at 0.889 0 90)
			(size 1.016 1.27)
			(layers "B.Cu" "B.Mask" "B.Paste")
			(net "PVDDCR_CPU0_P0")
		)
		(pad "2" smd rect
			(at -0.889 0 90)
			(size 1.016 1.27)
			(layers "B.Cu" "B.Mask" "B.Paste")
			(net "GND")
		)
	)
	(footprint ""
		(layer "B.Cu")
		(at 369.570254 -249.36831)
		(property "Reference" "C2177"
			(at 0 0 0)
			(layer "B.SilkS")
			(hide yes)
			(effects
				(font
					(size 1.27 1.27)
				)
				(justify mirror)
			)
		)
		(property "Value" ""
			(at 0 0 0)
			(layer "B.Fab")
			(effects
				(font
					(size 1.27 1.27)
				)
				(justify mirror)
			)
		)
		(duplicate_pad_numbers_are_jumpers no)
		(fp_line
			(start -0.7874 -0.4064)
			(end -0.7874 0.4064)
			(stroke
				(width 0.1524)
				(type default)
			)
			(layer "B.SilkS")
		)
		(fp_line
			(start -0.7874 0.4064)
			(end 0.7874 0.4064)
			(stroke
				(width 0.1524)
				(type default)
			)
			(layer "B.SilkS")
		)
		(fp_line
			(start 0.7874 -0.4064)
			(end -0.7874 -0.4064)
			(stroke
				(width 0.1524)
				(type default)
			)
			(layer "B.SilkS")
		)
		(fp_line
			(start 0.7874 0.4064)
			(end 0.7874 -0.4064)
			(stroke
				(width 0.1524)
				(type default)
			)
			(layer "B.SilkS")
		)
		(fp_line
			(start -0.67945 -0.3048)
			(end -0.67945 0.3048)
			(stroke
				(width 0.1)
				(type default)
			)
			(layer "B.Fab")
		)
		(fp_line
			(start -0.67945 0.3048)
			(end -0.120396 0.3048)
			(stroke
				(width 0.1)
				(type default)
			)
			(layer "B.Fab")
		)
		(fp_line
			(start -0.12065 -0.3048)
			(end -0.67945 -0.3048)
			(stroke
				(width 0.1)
				(type default)
			)
			(layer "B.Fab")
		)
		(fp_line
			(start -0.12065 -0.2794)
			(end -0.12065 -0.3048)
			(stroke
				(width 0.1)
				(type default)
			)
			(layer "B.Fab")
		)
		(fp_line
			(start -0.120396 0.2794)
			(end 0.12065 0.2794)
			(stroke
				(width 0.1)
				(type default)
			)
			(layer "B.Fab")
		)
		(fp_line
			(start -0.120396 0.3048)
			(end -0.120396 0.2794)
			(stroke
				(width 0.1)
				(type default)
			)
			(layer "B.Fab")
		)
		(fp_line
			(start 0.12065 -0.305054)
			(end 0.12065 -0.2794)
			(stroke
				(width 0.1)
				(type default)
			)
			(layer "B.Fab")
		)
		(fp_line
			(start 0.12065 -0.2794)
			(end -0.12065 -0.2794)
			(stroke
				(width 0.1)
				(type default)
			)
			(layer "B.Fab")
		)
		(fp_line
			(start 0.12065 0.2794)
			(end 0.12065 0.3048)
			(stroke
				(width 0.1)
				(type default)
			)
			(layer "B.Fab")
		)
		(fp_line
			(start 0.12065 0.3048)
			(end 0.67945 0.3048)
			(stroke
				(width 0.1)
				(type default)
			)
			(layer "B.Fab")
		)
		(fp_line
			(start 0.67945 -0.305054)
			(end 0.12065 -0.305054)
			(stroke
				(width 0.1)
				(type default)
			)
			(layer "B.Fab")
		)
		(fp_line
			(start 0.67945 0.3048)
			(end 0.67945 -0.305054)
			(stroke
				(width 0.1)
				(type default)
			)
			(layer "B.Fab")
		)
		(pad "1" smd circle
			(at 0.40005 0 180)
			(size 0 0)
			(layers "B.Cu" "B.Mask" "B.Paste")
			(net "PVDDCR_CPU0_P0")
		)
		(pad "2" smd circle
			(at -0.40005 0 180)
			(size 0 0)
			(layers "B.Cu" "B.Mask" "B.Paste")
			(net "GND")
		)
	)
	(footprint ""
		(layer "B.Cu")
		(at 421.00627 -395.148562 90)
		(property "Reference" "C786"
			(at 0 0 90)
			(layer "B.SilkS")
			(hide yes)
			(effects
				(font
					(size 1.27 1.27)
				)
				(justify mirror)
			)
		)
		(property "Value" ""
			(at 0 0 90)
			(layer "B.Fab")
			(effects
				(font
					(size 1.27 1.27)
				)
				(justify mirror)
			)
		)
		(duplicate_pad_numbers_are_jumpers no)
		(fp_line
			(start 0.299974 -0.150114)
			(end -0.299974 -0.150114)
			(stroke
				(width 0.1)
				(type default)
			)
			(layer "B.Fab")
		)
		(fp_line
			(start -0.299974 -0.150114)
			(end -0.299974 0.150114)
			(stroke
				(width 0.1)
				(type default)
			)
			(layer "B.Fab")
		)
		(fp_line
			(start 0.299974 0.150114)
			(end 0.299974 -0.150114)
			(stroke
				(width 0.1)
				(type default)
			)
			(layer "B.Fab")
		)
		(fp_line
			(start -0.299974 0.150114)
			(end 0.299974 0.150114)
			(stroke
				(width 0.1)
				(type default)
			)
			(layer "B.Fab")
		)
		(pad "1" smd rect
			(at 0.2667 0 270)
			(size 0.3048 0.381)
			(layers "B.Cu" "B.Mask" "B.Paste")
			(net "P0V9_CPU0_RT2_2A")
		)
		(pad "2" smd rect
			(at -0.2667 0 270)
			(size 0.3048 0.381)
			(layers "B.Cu" "B.Mask" "B.Paste")
			(net "GND")
		)
	)
	(footprint ""
		(layer "B.Cu")
		(at 83.460844 -337.643724 -90)
		(property "Reference" "PR261"
			(at 0 0 90)
			(layer "B.SilkS")
			(hide yes)
			(effects
				(font
					(size 1.27 1.27)
				)
				(justify mirror)
			)
		)
		(property "Value" ""
			(at 0 0 90)
			(layer "B.Fab")
			(effects
				(font
					(size 1.27 1.27)
				)
				(justify mirror)
			)
		)
		(duplicate_pad_numbers_are_jumpers no)
		(fp_line
			(start -0.7874 0.4064)
			(end 0.7874 0.4064)
			(stroke
				(width 0.1524)
				(type default)
			)
			(layer "B.SilkS")
		)
		(fp_line
			(start 0.7874 0.4064)
			(end 0.7874 -0.4064)
			(stroke
				(width 0.1524)
				(type default)
			)
			(layer "B.SilkS")
		)
		(fp_line
			(start -0.7874 -0.4064)
			(end -0.7874 0.4064)
			(stroke
				(width 0.1524)
				(type default)
			)
			(layer "B.SilkS")
		)
		(fp_line
			(start 0.7874 -0.4064)
			(end -0.7874 -0.4064)
			(stroke
				(width 0.1524)
				(type default)
			)
			(layer "B.SilkS")
		)
		(fp_line
			(start -0.67945 0.3048)
			(end -0.120396 0.3048)
			(stroke
				(width 0.1)
				(type default)
			)
			(layer "B.Fab")
		)
		(fp_line
			(start -0.120396 0.3048)
			(end -0.120396 0.2794)
			(stroke
				(width 0.1)
				(type default)
			)
			(layer "B.Fab")
		)
		(fp_line
			(start 0.12065 0.3048)
			(end 0.67945 0.3048)
			(stroke
				(width 0.1)
				(type default)
			)
			(layer "B.Fab")
		)
		(fp_line
			(start 0.67945 0.3048)
			(end 0.67945 -0.305054)
			(stroke
				(width 0.1)
				(type default)
			)
			(layer "B.Fab")
		)
		(fp_line
			(start -0.120396 0.2794)
			(end 0.12065 0.2794)
			(stroke
				(width 0.1)
				(type default)
			)
			(layer "B.Fab")
		)
		(fp_line
			(start 0.12065 0.2794)
			(end 0.12065 0.3048)
			(stroke
				(width 0.1)
				(type default)
			)
			(layer "B.Fab")
		)
		(fp_line
			(start -0.12065 -0.2794)
			(end -0.12065 -0.3048)
			(stroke
				(width 0.1)
				(type default)
			)
			(layer "B.Fab")
		)
		(fp_line
			(start 0.12065 -0.2794)
			(end -0.12065 -0.2794)
			(stroke
				(width 0.1)
				(type default)
			)
			(layer "B.Fab")
		)
		(fp_line
			(start -0.67945 -0.3048)
			(end -0.67945 0.3048)
			(stroke
				(width 0.1)
				(type default)
			)
			(layer "B.Fab")
		)
		(fp_line
			(start -0.12065 -0.3048)
			(end -0.67945 -0.3048)
			(stroke
				(width 0.1)
				(type default)
			)
			(layer "B.Fab")
		)
		(fp_line
			(start 0.12065 -0.305054)
			(end 0.12065 -0.2794)
			(stroke
				(width 0.1)
				(type default)
			)
			(layer "B.Fab")
		)
		(fp_line
			(start 0.67945 -0.305054)
			(end 0.12065 -0.305054)
			(stroke
				(width 0.1)
				(type default)
			)
			(layer "B.Fab")
		)
		(pad "1" smd circle
			(at 0.40005 0 90)
			(size 0 0)
			(layers "B.Cu" "B.Mask" "B.Paste")
			(net "PVDDCR_CPU1_P1_VOS1")
		)
		(pad "2" smd circle
			(at -0.40005 0 90)
			(size 0 0)
			(layers "B.Cu" "B.Mask" "B.Paste")
			(net "PVDDCR_CPU1_P1")
		)
	)
)
